FILE_TYPE = CONNECTIVITY;
{Allegro Design Entry HDL 17.2-2016 S081 (4005846) 1/11/2022}
"PAGE_NUMBER" = 82;
0"NC";
1"P12V_S3_AUX_CPU0_NVDIMM\g";
2"P12V_S3_AUX_CPU0_NVDIMM\g";
3"P3V3_AUX\g";
4"P3V3_AUX\g";
5"GND\g";
6"GND\g";
7"GND\g";
8"GND\g";
9"GND\g";
10"M_A_CPU0_SB_CB<7:0>";
11"M_A_CPU0_SA_CB<7:0>";
12"M_A_CPU0_SB_CA<6:0>";
13"M_A_CPU0_SA_CA<6:0>";
14"M_A_CPU0_SB_DQ<31:0>";
15"M_A_CPU0_SA_DQ<31:0>";
16"M_A_CPU0_SB_DQS_DN<9:0>";
17"M_A_CPU0_SB_DQS_DP<9:0>";
18"M_A_CPU0_SA_DQS_DP<9:0>";
19"M_A_CPU0_SA_DQS_DN<9:0>";
20"RST_M_AB_CPU0_FPGA_N";
21"M_A_CPU0_ALERT_N";
22"I3C_SPD_DDRABCD_CPU0_LVC1_SDA";
23"I3C_SPD_DDRABCD_CPU0_LVC1_SCL_R1";
24"I3C_SPD_DDRABCD_CPU0_LVC1_SCL";
25"PWRGD_CHA_CPU0_DIMM1";
26"PD_CHA_CPU0_DIMM1_SAA";
27"M_A_CPU0_SB_DQ<29>";
28"M_A_CPU0_SA_DQS_DN<9>";
29"M_A_CPU0_SA_DQS_DN<8>";
30"M_A_CPU0_SA_DQS_DP<9>";
31"M_A_CPU0_SA_DQS_DP<8>";
32"M_A_CPU0_SA_DQS_DP<7>";
33"M_A_CPU0_SA_DQS_DN<7>";
34"M_A_CPU0_SA_DQS_DN<5>";
35"M_A_CPU0_SA_DQS_DN<6>";
36"M_A_CPU0_SA_DQS_DP<6>";
37"M_A_CPU0_SA_DQS_DP<5>";
38"M_A_CPU0_SA_DQS_DN<4>";
39"M_A_CPU0_SA_DQS_DN<3>";
40"M_A_CPU0_SA_DQS_DP<4>";
41"M_A_CPU0_SA_DQS_DP<2>";
42"M_A_CPU0_SA_DQS_DP<3>";
43"M_A_CPU0_SA_DQS_DN<2>";
44"M_A_CPU0_SA_DQS_DN<1>";
45"M_A_CPU0_SA_DQS_DN<0>";
46"M_A_CPU0_SA_DQS_DP<1>";
47"M_A_CPU0_SA_DQS_DP<0>";
48"M_A_CPU0_SB_DQS_DN<9>";
49"M_A_CPU0_SB_DQS_DN<8>";
50"M_A_CPU0_SB_DQS_DP<9>";
51"M_A_CPU0_SB_DQS_DP<8>";
52"M_A_CPU0_SB_DQS_DN<6>";
53"M_A_CPU0_SB_DQS_DN<7>";
54"M_A_CPU0_SB_DQS_DP<7>";
55"M_A_CPU0_SB_DQS_DP<6>";
56"M_A_CPU0_SB_DQS_DP<5>";
57"M_A_CPU0_SB_DQS_DN<5>";
58"M_A_CPU0_SB_DQS_DN<4>";
59"M_A_CPU0_SB_DQS_DN<3>";
60"M_A_CPU0_SB_DQS_DP<4>";
61"M_A_CPU0_SB_DQS_DP<3>";
62"M_A_CPU0_SB_DQS_DN<2>";
63"M_A_CPU0_SB_DQS_DN<1>";
64"M_A_CPU0_SB_DQS_DP<2>";
65"M_A_CPU0_SB_DQS_DP<1>";
66"M_A_CPU0_SB_DQS_DP<0>";
67"M_A_CPU0_SB_DQS_DN<0>";
68"M_A_CPU0_SA_DQ<31>";
69"M_A_CPU0_SA_DQ<30>";
70"M_A_CPU0_SA_DQ<28>";
71"M_A_CPU0_SA_DQ<27>";
72"M_A_CPU0_SA_DQ<29>";
73"M_A_CPU0_SA_CA<5>";
74"M_A_CPU0_SA_CA<6>";
75"M_A_CPU0_SA_CA<4>";
76"M_A_CPU0_SA_CA<3>";
77"M_A_CPU0_SA_CA<2>";
78"M_A_CPU0_SA_DQ<26>";
79"M_A_CPU0_SA_DQ<25>";
80"M_A_CPU0_SA_DQ<24>";
81"M_A_CPU0_SA_DQ<23>";
82"M_A_CPU0_SA_DQ<22>";
83"M_A_CPU0_SA_DQ<21>";
84"M_A_CPU0_SA_DQ<20>";
85"M_A_CPU0_SA_DQ<17>";
86"M_A_CPU0_SA_DQ<18>";
87"M_A_CPU0_SA_DQ<19>";
88"M_A_CPU0_SA_DQ<15>";
89"M_A_CPU0_SA_DQ<16>";
90"M_A_CPU0_SA_DQ<12>";
91"M_A_CPU0_SA_DQ<14>";
92"M_A_CPU0_SA_DQ<13>";
93"M_A_CPU0_SA_DQ<10>";
94"M_A_CPU0_SA_DQ<11>";
95"M_A_CPU0_SA_DQ<9>";
96"M_A_CPU0_SA_DQ<7>";
97"M_A_CPU0_SA_DQ<8>";
98"M_A_CPU0_SA_DQ<6>";
99"M_A_CPU0_SA_DQ<5>";
100"M_A_CPU0_SA_DQ<4>";
101"M_A_CPU0_SA_DQ<3>";
102"M_A_CPU0_SA_DQ<2>";
103"M_A_CPU0_SA_DQ<1>";
104"M_A_CPU0_SA_DQ<0>";
105"M_A_CPU0_SB_DQ<30>";
106"M_A_CPU0_SB_DQ<31>";
107"M_A_CPU0_SB_DQ<28>";
108"M_A_CPU0_SB_DQ<27>";
109"M_A_CPU0_SB_DQ<26>";
110"M_A_CPU0_SB_DQ<25>";
111"M_A_CPU0_SB_DQ<22>";
112"M_A_CPU0_SB_DQ<24>";
113"M_A_CPU0_SB_DQ<23>";
114"M_A_CPU0_SB_DQ<20>";
115"M_A_CPU0_SB_DQ<21>";
116"M_A_CPU0_SB_DQ<19>";
117"M_A_CPU0_SB_DQ<18>";
118"M_A_CPU0_SB_DQ<17>";
119"M_A_CPU0_SB_DQ<16>";
120"M_A_CPU0_SB_DQ<15>";
121"M_A_CPU0_SB_DQ<14>";
122"M_A_CPU0_SB_DQ<13>";
123"M_A_CPU0_SB_DQ<12>";
124"M_A_CPU0_SB_DQ<11>";
125"M_A_CPU0_SB_DQ<10>";
126"M_A_CPU0_SB_DQ<9>";
127"M_A_CPU0_SB_DQ<8>";
128"M_A_CPU0_SB_DQ<7>";
129"M_A_CPU0_SB_DQ<4>";
130"M_A_CPU0_SB_DQ<5>";
131"M_A_CPU0_SB_DQ<6>";
132"M_A_CPU0_SB_DQ<2>";
133"M_A_CPU0_SB_DQ<3>";
134"M_A_CPU0_SB_DQ<1>";
135"M_A_CPU0_SB_DQ<0>";
136"M_A_CPU0_SA_CA<0>";
137"M_A_CPU0_SA_CA<1>";
138"M_A_CPU0_SB_CA<5>";
139"M_A_CPU0_SB_CA<6>";
140"M_A_CPU0_SB_CA<3>";
141"M_A_CPU0_SB_CA<4>";
142"M_A_CPU0_SB_CA<0>";
143"M_A_CPU0_SB_CA<1>";
144"M_A_CPU0_SB_CA<2>";
145"M_A_CPU0_SA_CB<6>";
146"M_A_CPU0_SA_CB<7>";
147"M_A_CPU0_SA_CB<5>";
148"M_A_CPU0_SA_CB<4>";
149"M_A_CPU0_SA_CB<3>";
150"M_A_CPU0_SA_CB<2>";
151"M_A_CPU0_SA_CB<1>";
152"M_A_CPU0_SA_CB<0>";
153"M_A_CPU0_SB_CB<7>";
154"M_A_CPU0_SB_CB<5>";
155"M_A_CPU0_SB_CB<6>";
156"M_A_CPU0_SB_CB<4>";
157"M_A_CPU0_SB_CB<3>";
158"M_A_CPU0_SB_CB<2>";
159"M_A_CPU0_SB_CB<0>";
160"M_A_CPU0_SB_CB<1>";
161"M_A_CPU0_SA_PAR";
162"M_A_CPU0_SB_PAR";
163"M_A_CPU0_SA_CS_N<1>";
164"M_A_CPU0_SB_CS_N<1>";
165"M_A_CPU0_SB_CS_N<0>";
166"M_A_CPU0_SA_CS_N<0>";
167"M_A_CPU0_CLK_DP<0>";
168"M_A_CPU0_CLK_DN<0>";
169"M_A_CPU0_SA_RSP<0>";
170"M_A_CPU0_SB_RSP<0>";
171"TP_CHA_CPU0_DIMM1_FRU_6";
172"TP_CHA_CPU0_DIMM1_FRU_5";
173"TP_CHA_CPU0_DIMM1_FRU_4";
174"TP_CHA_CPU0_DIMM1_FRU_3";
175"TP_CHA_CPU0_DIMM1_FRU_2";
176"TP_CHA_CPU0_DIMM1_FRU_1";
177"TP_CHA_CPU0_DIMM1_FRU_0";
178"PD_CHA_CPU0_DIMM1_SAA";
%"TAP"
"1","(-650,4200)","0","standard","I10";
;
CDS_LIB"standard"
BODY_TYPE"PLUMBING"
HDL_TAP"TRUE";
"B \NAC \NWC"15;
"S \NAC"
BN"29"72;
%"TAP"
"1","(2375,3200)","0","standard","I104";
;
CDS_LIB"standard"
BODY_TYPE"PLUMBING"
HDL_TAP"TRUE";
"B \NAC \NWC"16;
"S \NAC"
BN"9"48;
%"TAP"
"1","(2375,3100)","0","standard","I105";
;
CDS_LIB"standard"
BODY_TYPE"PLUMBING"
HDL_TAP"TRUE";
"B \NAC \NWC"16;
"S \NAC"
BN"8"49;
%"TAP"
"1","(2200,3250)","0","standard","I106";
;
CDS_LIB"standard"
BODY_TYPE"PLUMBING"
HDL_TAP"TRUE";
"B \NAC \NWC"17;
"S \NAC"
BN"9"50;
%"TAP"
"1","(2200,3050)","0","standard","I107";
;
CDS_LIB"standard"
BODY_TYPE"PLUMBING"
HDL_TAP"TRUE";
"B \NAC \NWC"17;
"S \NAC"
BN"7"54;
%"TAP"
"1","(2200,3150)","0","standard","I108";
;
CDS_LIB"standard"
BODY_TYPE"PLUMBING"
HDL_TAP"TRUE";
"B \NAC \NWC"17;
"S \NAC"
BN"8"51;
%"TAP"
"1","(2375,3000)","0","standard","I109";
;
CDS_LIB"standard"
BODY_TYPE"PLUMBING"
HDL_TAP"TRUE";
"B \NAC \NWC"16;
"S \NAC"
BN"7"53;
%"TAP"
"1","(-650,4250)","0","standard","I11";
;
CDS_LIB"standard"
BODY_TYPE"PLUMBING"
HDL_TAP"TRUE";
"B \NAC \NWC"15;
"S \NAC"
BN"30"69;
%"TAP"
"1","(2375,2900)","0","standard","I110";
;
CDS_LIB"standard"
BODY_TYPE"PLUMBING"
HDL_TAP"TRUE";
"B \NAC \NWC"16;
"S \NAC"
BN"6"52;
%"TAP"
"1","(2375,2800)","0","standard","I111";
;
CDS_LIB"standard"
BODY_TYPE"PLUMBING"
HDL_TAP"TRUE";
"B \NAC \NWC"16;
"S \NAC"
BN"5"57;
%"TAP"
"1","(2375,2700)","0","standard","I112";
;
CDS_LIB"standard"
BODY_TYPE"PLUMBING"
HDL_TAP"TRUE";
"B \NAC \NWC"16;
"S \NAC"
BN"4"58;
%"TAP"
"1","(2375,2600)","0","standard","I113";
;
CDS_LIB"standard"
BODY_TYPE"PLUMBING"
HDL_TAP"TRUE";
"B \NAC \NWC"16;
"S \NAC"
BN"3"59;
%"TAP"
"1","(2375,2500)","0","standard","I114";
;
CDS_LIB"standard"
BODY_TYPE"PLUMBING"
HDL_TAP"TRUE";
"B \NAC \NWC"16;
"S \NAC"
BN"2"62;
%"TAP"
"1","(2375,2300)","0","standard","I115";
;
CDS_LIB"standard"
BODY_TYPE"PLUMBING"
HDL_TAP"TRUE";
"B \NAC \NWC"16;
"S \NAC"
BN"0"67;
%"TAP"
"1","(2375,2400)","0","standard","I116";
;
CDS_LIB"standard"
BODY_TYPE"PLUMBING"
HDL_TAP"TRUE";
"B \NAC \NWC"16;
"S \NAC"
BN"1"63;
%"TAP"
"1","(2200,2950)","0","standard","I117";
;
CDS_LIB"standard"
BODY_TYPE"PLUMBING"
HDL_TAP"TRUE";
"B \NAC \NWC"17;
"S \NAC"
BN"6"55;
%"TAP"
"1","(2200,2850)","0","standard","I118";
;
CDS_LIB"standard"
BODY_TYPE"PLUMBING"
HDL_TAP"TRUE";
"B \NAC \NWC"17;
"S \NAC"
BN"5"56;
%"TAP"
"1","(2200,2750)","0","standard","I119";
;
CDS_LIB"standard"
BODY_TYPE"PLUMBING"
HDL_TAP"TRUE";
"B \NAC \NWC"17;
"S \NAC"
BN"4"60;
%"TAP"
"1","(-650,4300)","0","standard","I12";
;
CDS_LIB"standard"
BODY_TYPE"PLUMBING"
HDL_TAP"TRUE";
"B \NAC \NWC"15;
"S \NAC"
BN"31"68;
%"TAP"
"1","(2200,2550)","0","standard","I120";
;
CDS_LIB"standard"
BODY_TYPE"PLUMBING"
HDL_TAP"TRUE";
"B \NAC \NWC"17;
"S \NAC"
BN"2"64;
%"TAP"
"1","(2200,2650)","0","standard","I121";
;
CDS_LIB"standard"
BODY_TYPE"PLUMBING"
HDL_TAP"TRUE";
"B \NAC \NWC"17;
"S \NAC"
BN"3"61;
%"TAP"
"1","(2200,2450)","0","standard","I122";
;
CDS_LIB"standard"
BODY_TYPE"PLUMBING"
HDL_TAP"TRUE";
"B \NAC \NWC"17;
"S \NAC"
BN"1"65;
%"TAP"
"1","(2200,2350)","0","standard","I123";
;
CDS_LIB"standard"
BODY_TYPE"PLUMBING"
HDL_TAP"TRUE";
"B \NAC \NWC"17;
"S \NAC"
BN"0"66;
%"TAP"
"1","(-2300,4000)","2","standard","I124";
;
CDS_LIB"standard"
BODY_TYPE"PLUMBING"
HDL_TAP"TRUE";
"B \NAC \NWC"13;
"S \NAC"
BN"0"136;
%"TAP"
"1","(-2300,4050)","2","standard","I125";
;
CDS_LIB"standard"
BODY_TYPE"PLUMBING"
HDL_TAP"TRUE";
"B \NAC \NWC"13;
"S \NAC"
BN"1"137;
%"TAP"
"1","(-2300,4100)","2","standard","I126";
;
CDS_LIB"standard"
BODY_TYPE"PLUMBING"
HDL_TAP"TRUE";
"B \NAC \NWC"13;
"S \NAC"
BN"2"77;
%"TAP"
"1","(-2300,4200)","2","standard","I128";
;
CDS_LIB"standard"
BODY_TYPE"PLUMBING"
HDL_TAP"TRUE";
"B \NAC \NWC"13;
"S \NAC"
BN"4"75;
%"TAP"
"1","(-2300,4150)","2","standard","I129";
;
CDS_LIB"standard"
BODY_TYPE"PLUMBING"
HDL_TAP"TRUE";
"B \NAC \NWC"13;
"S \NAC"
BN"3"76;
%"TAP"
"1","(-650,4150)","0","standard","I13";
;
CDS_LIB"standard"
BODY_TYPE"PLUMBING"
HDL_TAP"TRUE";
"B \NAC \NWC"15;
"S \NAC"
BN"28"70;
%"TAP"
"1","(-2300,4250)","2","standard","I130";
;
CDS_LIB"standard"
BODY_TYPE"PLUMBING"
HDL_TAP"TRUE";
"B \NAC \NWC"13;
"S \NAC"
BN"5"73;
%"TAP"
"1","(-2300,4300)","2","standard","I131";
;
CDS_LIB"standard"
BODY_TYPE"PLUMBING"
HDL_TAP"TRUE";
"B \NAC \NWC"13;
"S \NAC"
BN"6"74;
%"TAP"
"1","(-2300,3600)","2","standard","I133";
;
CDS_LIB"standard"
BODY_TYPE"PLUMBING"
HDL_TAP"TRUE";
"B \NAC \NWC"12;
"S \NAC"
BN"0"142;
%"TAP"
"1","(-2300,3900)","2","standard","I134";
;
CDS_LIB"standard"
BODY_TYPE"PLUMBING"
HDL_TAP"TRUE";
"B \NAC \NWC"12;
"S \NAC"
BN"6"139;
%"TAP"
"1","(-2300,3850)","2","standard","I135";
;
CDS_LIB"standard"
BODY_TYPE"PLUMBING"
HDL_TAP"TRUE";
"B \NAC \NWC"12;
"S \NAC"
BN"5"138;
%"TAP"
"1","(-2300,3800)","2","standard","I136";
;
CDS_LIB"standard"
BODY_TYPE"PLUMBING"
HDL_TAP"TRUE";
"B \NAC \NWC"12;
"S \NAC"
BN"4"141;
%"TAP"
"1","(-2300,3750)","2","standard","I137";
;
CDS_LIB"standard"
BODY_TYPE"PLUMBING"
HDL_TAP"TRUE";
"B \NAC \NWC"12;
"S \NAC"
BN"3"140;
%"TAP"
"1","(-2300,3700)","2","standard","I138";
;
CDS_LIB"standard"
BODY_TYPE"PLUMBING"
HDL_TAP"TRUE";
"B \NAC \NWC"12;
"S \NAC"
BN"2"144;
%"TAP"
"1","(-2300,3650)","2","standard","I140";
;
CDS_LIB"standard"
BODY_TYPE"PLUMBING"
HDL_TAP"TRUE";
"B \NAC \NWC"12;
"S \NAC"
BN"1"143;
%"TAP"
"1","(-650,3700)","0","standard","I15";
;
CDS_LIB"standard"
BODY_TYPE"PLUMBING"
HDL_TAP"TRUE";
"B \NAC \NWC"15;
"S \NAC"
BN"19"87;
%"TAP"
"1","(-2300,2600)","2","standard","I157";
;
CDS_LIB"standard"
BODY_TYPE"PLUMBING"
HDL_TAP"TRUE";
"B \NAC \NWC"11;
"S \NAC"
BN"1"151;
%"TAP"
"1","(-2300,2650)","2","standard","I158";
;
CDS_LIB"standard"
BODY_TYPE"PLUMBING"
HDL_TAP"TRUE";
"B \NAC \NWC"11;
"S \NAC"
BN"2"150;
%"TAP"
"1","(-650,3750)","0","standard","I16";
;
CDS_LIB"standard"
BODY_TYPE"PLUMBING"
HDL_TAP"TRUE";
"B \NAC \NWC"15;
"S \NAC"
BN"20"84;
%"TAP"
"1","(-2300,2700)","2","standard","I160";
;
CDS_LIB"standard"
BODY_TYPE"PLUMBING"
HDL_TAP"TRUE";
"B \NAC \NWC"11;
"S \NAC"
BN"3"149;
%"TAP"
"1","(-2300,2750)","2","standard","I161";
;
CDS_LIB"standard"
BODY_TYPE"PLUMBING"
HDL_TAP"TRUE";
"B \NAC \NWC"11;
"S \NAC"
BN"4"148;
%"TAP"
"1","(-2300,2800)","2","standard","I162";
;
CDS_LIB"standard"
BODY_TYPE"PLUMBING"
HDL_TAP"TRUE";
"B \NAC \NWC"11;
"S \NAC"
BN"5"147;
%"TAP"
"1","(-2300,2850)","2","standard","I163";
;
CDS_LIB"standard"
BODY_TYPE"PLUMBING"
HDL_TAP"TRUE";
"B \NAC \NWC"11;
"S \NAC"
BN"6"145;
%"TAP"
"1","(-2300,2900)","2","standard","I164";
;
CDS_LIB"standard"
BODY_TYPE"PLUMBING"
HDL_TAP"TRUE";
"B \NAC \NWC"11;
"S \NAC"
BN"7"146;
%"TAP"
"1","(-2300,2550)","2","standard","I165";
;
CDS_LIB"standard"
BODY_TYPE"PLUMBING"
HDL_TAP"TRUE";
"B \NAC \NWC"11;
"S \NAC"
BN"0"152;
%"TAP"
"1","(-2300,2100)","2","standard","I167";
;
CDS_LIB"standard"
BODY_TYPE"PLUMBING"
HDL_TAP"TRUE";
"B \NAC \NWC"10;
"S \NAC"
BN"0"159;
%"TAP"
"1","(-2300,2450)","2","standard","I168";
;
CDS_LIB"standard"
BODY_TYPE"PLUMBING"
HDL_TAP"TRUE";
"B \NAC \NWC"10;
"S \NAC"
BN"7"153;
%"TAP"
"1","(-2300,2400)","2","standard","I169";
;
CDS_LIB"standard"
BODY_TYPE"PLUMBING"
HDL_TAP"TRUE";
"B \NAC \NWC"10;
"S \NAC"
BN"6"155;
%"TAP"
"1","(-650,3800)","0","standard","I17";
;
CDS_LIB"standard"
BODY_TYPE"PLUMBING"
HDL_TAP"TRUE";
"B \NAC \NWC"15;
"S \NAC"
BN"21"83;
%"TAP"
"1","(-2300,2350)","2","standard","I170";
;
CDS_LIB"standard"
BODY_TYPE"PLUMBING"
HDL_TAP"TRUE";
"B \NAC \NWC"10;
"S \NAC"
BN"5"154;
%"TAP"
"1","(-2300,2300)","2","standard","I171";
;
CDS_LIB"standard"
BODY_TYPE"PLUMBING"
HDL_TAP"TRUE";
"B \NAC \NWC"10;
"S \NAC"
BN"4"156;
%"TAP"
"1","(-2300,2250)","2","standard","I172";
;
CDS_LIB"standard"
BODY_TYPE"PLUMBING"
HDL_TAP"TRUE";
"B \NAC \NWC"10;
"S \NAC"
BN"3"157;
%"TAP"
"1","(-2300,2200)","2","standard","I173";
;
CDS_LIB"standard"
BODY_TYPE"PLUMBING"
HDL_TAP"TRUE";
"B \NAC \NWC"10;
"S \NAC"
BN"2"158;
%"TAP"
"1","(-2300,2150)","2","standard","I174";
;
CDS_LIB"standard"
BODY_TYPE"PLUMBING"
HDL_TAP"TRUE";
"B \NAC \NWC"10;
"S \NAC"
BN"1"160;
%"TAP"
"1","(-650,3650)","0","standard","I18";
;
CDS_LIB"standard"
BODY_TYPE"PLUMBING"
HDL_TAP"TRUE";
"B \NAC \NWC"15;
"S \NAC"
BN"18"86;
%"VCC_CORE"
"1","(-3125,2175)","0","logical_power","I183";
;
HDL_POWER"P3V3_AUX"
CDS_LIB"logical_power";
"A"4;
%"UNIVERSAL_GND"
"1","(5475,600)","0","logical_power","I184";
;
CDS_LIB"logical_power"
HDL_POWER"GND";
"A"5;
%"UNIVERSAL_GND"
"1","(3775,600)","0","logical_power","I185";
;
CDS_LIB"logical_power"
HDL_POWER"GND";
"A"6;
%"VCC_CORE"
"1","(3775,4850)","0","logical_power","I186";
;
HDL_POWER"P12V_S3_AUX_CPU0_NVDIMM"
CDS_LIB"logical_power";
"A"1;
%"VCC_CORE"
"1","(2075,750)","0","logical_power","I187";
;
HDL_POWER"P12V_S3_AUX_CPU0_NVDIMM"
CDS_LIB"logical_power";
"A"2;
%"Q_CAP"
"1","(2075,425)","0","pure_quanta","I188";
;
PART_NUMBER"CH6103KEA00"
MATERIAL"X6S"
PACK_TYPE"C0805"
TOLERANCE"10%"
VALUE"10UF"
VOLTAGE"16V"
$LOCATION"C3"
CDS_LIB"pure_quanta"
CDS_LOCATION"C3"
$SEC"1"
CDS_SEC"1";
"B"
$PN"2"9;
"A"
$PN"1"2;
%"TAP"
"1","(-650,3600)","0","standard","I19";
;
CDS_LIB"standard"
BODY_TYPE"PLUMBING"
HDL_TAP"TRUE";
"B \NAC \NWC"15;
"S \NAC"
BN"17"85;
%"Q_CAP"
"1","(2700,425)","0","pure_quanta","I190";
;
PART_NUMBER"CH6103KEA00"
MATERIAL"X6S"
PACK_TYPE"C0805"
VOLTAGE"16V"
VALUE"10UF"
TOLERANCE"10%"
$LOCATION"C4"
CDS_LIB"pure_quanta"
CDS_LOCATION"C4"
$SEC"1"
CDS_SEC"1";
"B"
$PN"2"9;
"A"
$PN"1"2;
%"UNIVERSAL_GND"
"1","(2700,50)","0","logical_power","I191";
;
CDS_LIB"logical_power"
HDL_POWER"GND";
"A"9;
%"Q_CAP"
"1","(1075,425)","0","pure_quanta","I192";
;
PART_NUMBER"CH5221MEB00"
MATERIAL"X6S"
VOLTAGE"6.3V"
PACK_TYPE"C0402"
VALUE"2.2UF"
TOLERANCE"20%"
$LOCATION"C2"
CDS_LIB"pure_quanta"
CDS_LOCATION"C2"
$SEC"1"
CDS_SEC"1";
"B"
$PN"2"8;
"A"
$PN"1"3;
%"VCC_CORE"
"1","(1075,750)","0","logical_power","I193";
;
HDL_POWER"P3V3_AUX"
CDS_LIB"logical_power";
"A"3;
%"UNIVERSAL_GND"
"1","(1075,50)","0","logical_power","I194";
;
CDS_LIB"logical_power"
HDL_POWER"GND";
"A"8;
%"Q_RES"
"2","(-2075,150)","0","pure_quanta","I196";
;
PART_NUMBER"CS31002FB08"
WATTAGE"1/16W"
MATERIAL"CHIP"
TOLERANCE"1%"
VALUE"10K"
PACK_TYPE"0402LF"
$LOCATION"R26"
CDS_LIB"pure_quanta"
CDS_LOCATION"R26"
$SEC"1"
CDS_SEC"1";
"A"
$PN"1"178;
"B"
$PN"2"7;
%"UNIVERSAL_GND"
"1","(-2075,-75)","0","logical_power","I197";
;
CDS_LIB"logical_power"
HDL_POWER"GND";
"A"7;
%"SCONN288_ADR50017P130CC"
"1","(-1475,2575)","0","pure_quanta","I198";
;
PART_NUMBER"DFHST8FS461"
VALUE"SCONN288_ADR50017-P130CC"
MATERIAL"IO"
PART_TYPE"SMLF"
$LOCATION"J1"
CDS_LIB"pure_quanta"
CDS_LMAN_SYM_OUTLINE"-450,1875,450,-1875"
NEEDS_NO_SIZE"TRUE"
CDS_LOCATION"J1"
$SEC"1"
CDS_SEC"1";
"DQ31_A"
$PN"194"68;
"CB7_A"
$PN"205"146;
"CB4_A"
$PN"58"148;
"CB1_A"
$PN"53"151;
"CB7_B"
$PN"236"153;
"ALERT_N \B"
$PN"62"21;
"CA0_A"
$PN"66"136;
"CA0_B"
$PN"76"142;
"CA1_A"
$PN"211"137;
"CA1_B"
$PN"221"143;
"CA2_A"
$PN"68"77;
"CA2_B"
$PN"78"144;
"CA3_A"
$PN"213"76;
"CA3_B"
$PN"223"140;
"CA4_A"
$PN"70"75;
"CA4_B"
$PN"80"141;
"CA5_A"
$PN"215"73;
"CA5_B"
$PN"225"138;
"CA6_A"
$PN"72"74;
"CA6_B"
$PN"82"139;
"CB6_A"
$PN"203"145;
"CB5_A"
$PN"60"147;
"CB3_A"
$PN"198"149;
"CB2_A"
$PN"196"150;
"CB0_A"
$PN"51"152;
"CB6_B"
$PN"234"155;
"CB5_B"
$PN"91"154;
"CB4_B"
$PN"89"156;
"CB3_B"
$PN"243"157;
"CB2_B"
$PN"241"158;
"CB1_B"
$PN"98"160;
"CB0_B"
$PN"96"159;
"CK_C \B"
$PN"218"168;
"CK_T"
$PN"217"167;
"CS0_A_N"
$PN"64"166;
"CS0_B_N"
$PN"84"165;
"CS1_A_N"
$PN"209"163;
"CS1_B_N"
$PN"229"164;
"DQ30_A"
$PN"192"69;
"DQ29_A"
$PN"49"72;
"DQ28_A"
$PN"47"70;
"DQ27_A"
$PN"187"71;
"DQ26_A"
$PN"185"78;
"DQ25_A"
$PN"42"79;
"DQ24_A"
$PN"40"80;
"DQ23_A"
$PN"183"81;
"DQ22_A"
$PN"181"82;
"DQ21_A"
$PN"38"83;
"DQ20_A"
$PN"36"84;
"DQ19_A"
$PN"176"87;
"DQ18_A"
$PN"174"86;
"DQ17_A"
$PN"31"85;
"DQ16_A"
$PN"29"89;
"DQ15_A"
$PN"172"88;
"DQ14_A"
$PN"170"91;
"DQ13_A"
$PN"27"92;
"DQ12_A"
$PN"25"90;
"DQ11_A"
$PN"165"94;
"DQ10_A"
$PN"163"93;
"DQ9_A"
$PN"20"95;
"DQ8_A"
$PN"18"97;
"DQ7_A"
$PN"161"96;
"DQ6_A"
$PN"159"98;
"DQ5_A"
$PN"16"99;
"DQ4_A"
$PN"14"100;
"DQ3_A"
$PN"154"101;
"DQ2_A"
$PN"152"102;
"DQ1_A"
$PN"9"103;
"DQ0_A"
$PN"7"104;
"DQ31_B"
$PN"287"106;
"DQ30_B"
$PN"285"105;
"DQ29_B"
$PN"142"27;
"DQ28_B"
$PN"140"107;
"DQ27_B"
$PN"280"108;
"DQ26_B"
$PN"278"109;
"DQ25_B"
$PN"135"110;
"DQ24_B"
$PN"133"112;
"DQ23_B"
$PN"276"113;
"DQ22_B"
$PN"274"111;
"DQ21_B"
$PN"131"115;
"DQ20_B"
$PN"129"114;
"DQ19_B"
$PN"269"116;
"DQ18_B"
$PN"267"117;
"DQ17_B"
$PN"124"118;
"DQ16_B"
$PN"122"119;
"DQ15_B"
$PN"265"120;
"DQ14_B"
$PN"263"121;
"DQ13_B"
$PN"120"122;
"DQ12_B"
$PN"118"123;
"DQ11_B"
$PN"258"124;
"DQ10_B"
$PN"256"125;
"DQ9_B"
$PN"113"126;
"DQ8_B"
$PN"111"127;
"DQ7_B"
$PN"254"128;
"DQ6_B"
$PN"252"131;
"DQ5_B"
$PN"109"130;
"DQ4_B"
$PN"107"129;
"DQ3_B"
$PN"247"133;
"DQ2_B"
$PN"245"132;
"DQ1_B"
$PN"102"134;
"DQ0_B"
$PN"100"135;
"HSA"
$PN"148"26;
"HSCL"
$PN"4"23;
"HSDA"
$PN"5"22;
"LBD||RSP_A_N"
$PN"86"169;
"LBS||RSP_B_N"
$PN"87"170;
"PAR_A"
$PN"74"161;
"PAR_B"
$PN"227"162;
"PWR_GOOD||FAIL_N"
$PN"147"25;
"RESET_N \B"
$PN"207"20;
"RFU6"
$PN"232"171;
"RFU5"
$PN"231"172;
"RFU4"
$PN"220"173;
"RFU3"
$PN"150"174;
"RFU2"
$PN"149"175;
"RFU1"
$PN"144"176;
"RFU0"
$PN"2"177;
"VIN_MGMT"
$PN"3"4;
%"TAP"
"1","(-650,3550)","0","standard","I20";
;
CDS_LIB"standard"
BODY_TYPE"PLUMBING"
HDL_TAP"TRUE";
"B \NAC \NWC"15;
"S \NAC"
BN"16"89;
%"SCONN288_ADR50017P130CC"
"2","(1300,3300)","0","pure_quanta","I202";
;
PART_NUMBER"DFHST8FS461"
MATERIAL"IO"
PART_TYPE"SMLF"
VALUE"SCONN288_ADR50017-P130CC"
LOCATION"J1"
CDS_LIB"pure_quanta"
CDS_LMAN_SYM_OUTLINE"-600,1150,600,-1150"
NEEDS_NO_SIZE"TRUE"
$SEC"2"
CDS_SEC"2";
"DQS7_A_C||TDQS7_A_C \B"
$PN"178"33;
"DQS6_A_T||TDQS6_A_T"
$PN"168"36;
"DQS8_B_T||TDQS8_B_T"
$PN"283"51;
"DQS8_B_C||TDQS8_B_C \B"
$PN"282"49;
"DQS7_B_T||TDQS7_B_T"
$PN"272"54;
"DQS0_A_C \B"
$PN"12"45;
"DQS0_A_T"
$PN"11"47;
"DQS0_B_C \B"
$PN"105"67;
"DQS0_B_T"
$PN"104"66;
"DQS1_A_C \B"
$PN"23"44;
"DQS1_A_T"
$PN"22"46;
"DQS1_B_C \B"
$PN"116"63;
"DQS1_B_T"
$PN"115"65;
"DQS2_A_C \B"
$PN"34"43;
"DQS2_A_T"
$PN"33"41;
"DQS2_B_C \B"
$PN"127"62;
"DQS2_B_T"
$PN"126"64;
"DQS3_A_C \B"
$PN"45"39;
"DQS3_A_T"
$PN"44"42;
"DQS3_B_C \B"
$PN"138"59;
"DQS3_B_T"
$PN"137"61;
"DQS4_A_C \B"
$PN"56"38;
"DQS4_A_T"
$PN"55"40;
"DQS4_B_C \B"
$PN"238"58;
"DQS4_B_T"
$PN"239"60;
"DQS5_A_C||TDQS5_A_C||DQS5_A_T||TDQS5_A_T \B"
$PN"156"34;
"DQS5_A_T||TDQS5_A_T"
$PN"157"37;
"DQS5_B_C||TDQS5_B_C \B"
$PN"249"57;
"DQS5_B_T||TDQS5_B_T"
$PN"250"56;
"DQS6_A_C||TDQS6_A_C||DQS6_A_T||TDQS6_A_T \B"
$PN"167"35;
"DQS6_B_C||TDQS6_B_C \B"
$PN"260"52;
"DQS6_B_T||TDQS6_B_T"
$PN"261"55;
"DQS7_A_T||TDQS7_A_T"
$PN"179"32;
"DQS7_B_C||TDQS7_B_C \B"
$PN"271"53;
"DQS8_A_C||TDQS8_A_C \B"
$PN"189"29;
"DQS8_A_T||TDQS8_A_T"
$PN"190"31;
"DQS9_A_C||TDQS9_A_C \B"
$PN"200"28;
"DQS9_A_T||TDQS9_A_T"
$PN"201"30;
"DQS9_B_C||TDQS9_B_C \B"
$PN"94"48;
"DQS9_B_T||TDQS9_B_T||DBI4_B_N"
$PN"93"50;
%"SCONN288_ADR50017P130CC"
"3","(4625,2675)","0","pure_quanta","I203";
;
PART_NUMBER"DFHST8FS461"
PART_TYPE"SMLF"
MATERIAL"IO"
VALUE"SCONN288_ADR50017-P130CC"
LOCATION"J1"
CDS_LIB"pure_quanta"
CDS_LMAN_SYM_OUTLINE"-450,1775,450,-1775"
NEEDS_NO_SIZE"TRUE"
$SEC"3"
CDS_SEC"3";
"G3"
$PN"G3"5;
"G2"
$PN"G2"5;
"G1"
$PN"G1"5;
"VSS62"
$PN"141"5;
"VSS61"
$PN"139"5;
"VSS60"
$PN"136"5;
"VSS58"
$PN"132"5;
"VSS104"
$PN"240"6;
"VSS102"
$PN"235"6;
"VSS100"
$PN"230"6;
"VIN_BULK2"
$PN"146"1;
"VIN_BULK1"
$PN"145"1;
"VIN_BULK0"
$PN"1"1;
"VSS126"
$PN"288"6;
"VSS125"
$PN"286"6;
"VSS124"
$PN"284"6;
"VSS123"
$PN"281"6;
"VSS122"
$PN"279"6;
"VSS121"
$PN"277"6;
"VSS120"
$PN"275"6;
"VSS119"
$PN"273"6;
"VSS118"
$PN"270"6;
"VSS117"
$PN"268"6;
"VSS116"
$PN"266"6;
"VSS115"
$PN"264"6;
"VSS114"
$PN"262"6;
"VSS113"
$PN"259"6;
"VSS112"
$PN"257"6;
"VSS111"
$PN"255"6;
"VSS110"
$PN"253"6;
"VSS109"
$PN"251"6;
"VSS108"
$PN"248"6;
"VSS107"
$PN"246"6;
"VSS106"
$PN"244"6;
"VSS105"
$PN"242"6;
"VSS103"
$PN"237"6;
"VSS101"
$PN"233"6;
"VSS99"
$PN"228"6;
"VSS98"
$PN"226"6;
"VSS97"
$PN"224"6;
"VSS96"
$PN"222"6;
"VSS95"
$PN"219"6;
"VSS94"
$PN"216"6;
"VSS93"
$PN"214"6;
"VSS92"
$PN"212"6;
"VSS91"
$PN"210"6;
"VSS90"
$PN"208"6;
"VSS89"
$PN"206"6;
"VSS88"
$PN"204"6;
"VSS87"
$PN"202"6;
"VSS86"
$PN"199"6;
"VSS85"
$PN"197"6;
"VSS84"
$PN"195"6;
"VSS83"
$PN"193"6;
"VSS82"
$PN"191"6;
"VSS81"
$PN"188"6;
"VSS80"
$PN"186"6;
"VSS79"
$PN"184"6;
"VSS78"
$PN"182"6;
"VSS77"
$PN"180"6;
"VSS76"
$PN"177"6;
"VSS75"
$PN"175"6;
"VSS74"
$PN"173"6;
"VSS73"
$PN"171"6;
"VSS72"
$PN"169"6;
"VSS71"
$PN"166"6;
"VSS70"
$PN"164"6;
"VSS69"
$PN"162"6;
"VSS68"
$PN"160"6;
"VSS67"
$PN"158"6;
"VSS66"
$PN"155"6;
"VSS65"
$PN"153"6;
"VSS64"
$PN"151"6;
"VSS63"
$PN"143"5;
"VSS59"
$PN"134"5;
"VSS57"
$PN"130"5;
"VSS56"
$PN"128"5;
"VSS55"
$PN"125"5;
"VSS54"
$PN"123"5;
"VSS53"
$PN"121"5;
"VSS52"
$PN"119"5;
"VSS51"
$PN"117"5;
"VSS50"
$PN"114"5;
"VSS49"
$PN"112"5;
"VSS48"
$PN"110"5;
"VSS47"
$PN"108"5;
"VSS46"
$PN"106"5;
"VSS45"
$PN"103"5;
"VSS44"
$PN"101"5;
"VSS43"
$PN"99"5;
"VSS42"
$PN"97"5;
"VSS41"
$PN"95"5;
"VSS40"
$PN"92"5;
"VSS39"
$PN"90"5;
"VSS38"
$PN"88"5;
"VSS37"
$PN"85"5;
"VSS36"
$PN"83"5;
"VSS35"
$PN"81"5;
"VSS34"
$PN"79"5;
"VSS33"
$PN"77"5;
"VSS32"
$PN"75"5;
"VSS31"
$PN"73"5;
"VSS30"
$PN"71"5;
"VSS29"
$PN"69"5;
"VSS28"
$PN"67"5;
"VSS27"
$PN"65"5;
"VSS26"
$PN"63"5;
"VSS25"
$PN"61"5;
"VSS24"
$PN"59"5;
"VSS23"
$PN"57"5;
"VSS22"
$PN"54"5;
"VSS21"
$PN"52"5;
"VSS20"
$PN"50"5;
"VSS19"
$PN"48"5;
"VSS18"
$PN"46"5;
"VSS17"
$PN"43"5;
"VSS16"
$PN"41"5;
"VSS15"
$PN"39"5;
"VSS14"
$PN"37"5;
"VSS13"
$PN"35"5;
"VSS12"
$PN"32"5;
"VSS11"
$PN"30"5;
"VSS10"
$PN"28"5;
"VSS9"
$PN"26"5;
"VSS8"
$PN"24"5;
"VSS7"
$PN"21"5;
"VSS6"
$PN"19"5;
"VSS5"
$PN"17"5;
"VSS4"
$PN"15"5;
"VSS3"
$PN"13"5;
"VSS2"
$PN"10"5;
"VSS1"
$PN"8"5;
"VSS0"
$PN"6"5;
%"Q_RES"
"1","(-3275,1625)","0","pure_quanta","I204";
;
PART_NUMBER"CS04992FB07"
VALUE"49.9"
MATERIAL"CHIP"
TOLERANCE"1%"
$LOCATION"R3875"
WATTAGE"1/16W"
PACK_TYPE"0402LF"
CDS_LIB"pure_quanta"
CDS_LOCATION"R3875"
$SEC"1"
CDS_SEC"1";
"B"
$PN"2"24;
"A"
$PN"1"23;
%"TAP"
"1","(-650,3400)","0","standard","I21";
;
CDS_LIB"standard"
BODY_TYPE"PLUMBING"
HDL_TAP"TRUE";
"B \NAC \NWC"15;
"S \NAC"
BN"13"92;
%"TAP"
"1","(-650,3500)","0","standard","I22";
;
CDS_LIB"standard"
BODY_TYPE"PLUMBING"
HDL_TAP"TRUE";
"B \NAC \NWC"15;
"S \NAC"
BN"15"88;
%"TAP"
"1","(-650,3450)","0","standard","I23";
;
CDS_LIB"standard"
BODY_TYPE"PLUMBING"
HDL_TAP"TRUE";
"B \NAC \NWC"15;
"S \NAC"
BN"14"91;
%"TAP"
"1","(-650,2800)","0","standard","I24";
;
CDS_LIB"standard"
BODY_TYPE"PLUMBING"
HDL_TAP"TRUE";
"B \NAC \NWC"15;
"S \NAC"
BN"1"103;
%"TAP"
"1","(-650,2850)","0","standard","I25";
;
CDS_LIB"standard"
BODY_TYPE"PLUMBING"
HDL_TAP"TRUE";
"B \NAC \NWC"15;
"S \NAC"
BN"2"102;
%"TAP"
"1","(-650,2750)","0","standard","I26";
;
CDS_LIB"standard"
BODY_TYPE"PLUMBING"
HDL_TAP"TRUE";
"B \NAC \NWC"15;
"S \NAC"
BN"0"104;
%"TAP"
"1","(-650,2900)","0","standard","I27";
;
CDS_LIB"standard"
BODY_TYPE"PLUMBING"
HDL_TAP"TRUE";
"B \NAC \NWC"15;
"S \NAC"
BN"3"101;
%"TAP"
"1","(-650,2950)","0","standard","I28";
;
CDS_LIB"standard"
BODY_TYPE"PLUMBING"
HDL_TAP"TRUE";
"B \NAC \NWC"15;
"S \NAC"
BN"4"100;
%"TAP"
"1","(-650,3000)","0","standard","I29";
;
CDS_LIB"standard"
BODY_TYPE"PLUMBING"
HDL_TAP"TRUE";
"B \NAC \NWC"15;
"S \NAC"
BN"5"99;
%"TAP"
"1","(-650,3150)","0","standard","I30";
;
CDS_LIB"standard"
BODY_TYPE"PLUMBING"
HDL_TAP"TRUE";
"B \NAC \NWC"15;
"S \NAC"
BN"8"97;
%"TAP"
"1","(-650,3100)","0","standard","I31";
;
CDS_LIB"standard"
BODY_TYPE"PLUMBING"
HDL_TAP"TRUE";
"B \NAC \NWC"15;
"S \NAC"
BN"7"96;
%"TAP"
"1","(-650,3050)","0","standard","I32";
;
CDS_LIB"standard"
BODY_TYPE"PLUMBING"
HDL_TAP"TRUE";
"B \NAC \NWC"15;
"S \NAC"
BN"6"98;
%"TAP"
"1","(-650,3200)","0","standard","I33";
;
CDS_LIB"standard"
BODY_TYPE"PLUMBING"
HDL_TAP"TRUE";
"B \NAC \NWC"15;
"S \NAC"
BN"9"95;
%"TAP"
"1","(-650,3350)","0","standard","I34";
;
CDS_LIB"standard"
BODY_TYPE"PLUMBING"
HDL_TAP"TRUE";
"B \NAC \NWC"15;
"S \NAC"
BN"12"90;
%"TAP"
"1","(-650,3300)","0","standard","I35";
;
CDS_LIB"standard"
BODY_TYPE"PLUMBING"
HDL_TAP"TRUE";
"B \NAC \NWC"15;
"S \NAC"
BN"11"94;
%"TAP"
"1","(-650,3250)","0","standard","I36";
;
CDS_LIB"standard"
BODY_TYPE"PLUMBING"
HDL_TAP"TRUE";
"B \NAC \NWC"15;
"S \NAC"
BN"10"93;
%"TAP"
"1","(-650,1150)","0","standard","I37";
;
CDS_LIB"standard"
BODY_TYPE"PLUMBING"
HDL_TAP"TRUE";
"B \NAC \NWC"14;
"S \NAC"
BN"1"134;
%"TAP"
"1","(-650,1250)","0","standard","I38";
;
CDS_LIB"standard"
BODY_TYPE"PLUMBING"
HDL_TAP"TRUE";
"B \NAC \NWC"14;
"S \NAC"
BN"3"133;
%"TAP"
"1","(-650,1200)","0","standard","I39";
;
CDS_LIB"standard"
BODY_TYPE"PLUMBING"
HDL_TAP"TRUE";
"B \NAC \NWC"14;
"S \NAC"
BN"2"132;
%"TAP"
"1","(-650,3850)","0","standard","I4";
;
CDS_LIB"standard"
BODY_TYPE"PLUMBING"
HDL_TAP"TRUE";
"B \NAC \NWC"15;
"S \NAC"
BN"22"82;
%"TAP"
"1","(-650,1400)","0","standard","I40";
;
CDS_LIB"standard"
BODY_TYPE"PLUMBING"
HDL_TAP"TRUE";
"B \NAC \NWC"14;
"S \NAC"
BN"6"131;
%"TAP"
"1","(-650,1350)","0","standard","I41";
;
CDS_LIB"standard"
BODY_TYPE"PLUMBING"
HDL_TAP"TRUE";
"B \NAC \NWC"14;
"S \NAC"
BN"5"130;
%"TAP"
"1","(-650,1300)","0","standard","I42";
;
CDS_LIB"standard"
BODY_TYPE"PLUMBING"
HDL_TAP"TRUE";
"B \NAC \NWC"14;
"S \NAC"
BN"4"129;
%"TAP"
"1","(-650,1450)","0","standard","I43";
;
CDS_LIB"standard"
BODY_TYPE"PLUMBING"
HDL_TAP"TRUE";
"B \NAC \NWC"14;
"S \NAC"
BN"7"128;
%"TAP"
"1","(-650,1500)","0","standard","I44";
;
CDS_LIB"standard"
BODY_TYPE"PLUMBING"
HDL_TAP"TRUE";
"B \NAC \NWC"14;
"S \NAC"
BN"8"127;
%"TAP"
"1","(-650,1550)","0","standard","I45";
;
CDS_LIB"standard"
BODY_TYPE"PLUMBING"
HDL_TAP"TRUE";
"B \NAC \NWC"14;
"S \NAC"
BN"9"126;
%"TAP"
"1","(-650,1600)","0","standard","I46";
;
CDS_LIB"standard"
BODY_TYPE"PLUMBING"
HDL_TAP"TRUE";
"B \NAC \NWC"14;
"S \NAC"
BN"10"125;
%"TAP"
"1","(-650,1650)","0","standard","I47";
;
CDS_LIB"standard"
BODY_TYPE"PLUMBING"
HDL_TAP"TRUE";
"B \NAC \NWC"14;
"S \NAC"
BN"11"124;
%"TAP"
"1","(-650,1700)","0","standard","I48";
;
CDS_LIB"standard"
BODY_TYPE"PLUMBING"
HDL_TAP"TRUE";
"B \NAC \NWC"14;
"S \NAC"
BN"12"123;
%"TAP"
"1","(-650,1800)","0","standard","I49";
;
CDS_LIB"standard"
BODY_TYPE"PLUMBING"
HDL_TAP"TRUE";
"B \NAC \NWC"14;
"S \NAC"
BN"14"121;
%"TAP"
"1","(-650,3900)","0","standard","I5";
;
CDS_LIB"standard"
BODY_TYPE"PLUMBING"
HDL_TAP"TRUE";
"B \NAC \NWC"15;
"S \NAC"
BN"23"81;
%"TAP"
"1","(-650,1750)","0","standard","I50";
;
CDS_LIB"standard"
BODY_TYPE"PLUMBING"
HDL_TAP"TRUE";
"B \NAC \NWC"14;
"S \NAC"
BN"13"122;
%"TAP"
"1","(-650,1850)","0","standard","I51";
;
CDS_LIB"standard"
BODY_TYPE"PLUMBING"
HDL_TAP"TRUE";
"B \NAC \NWC"14;
"S \NAC"
BN"15"120;
%"TAP"
"1","(-650,1900)","0","standard","I52";
;
CDS_LIB"standard"
BODY_TYPE"PLUMBING"
HDL_TAP"TRUE";
"B \NAC \NWC"14;
"S \NAC"
BN"16"119;
%"TAP"
"1","(-650,1950)","0","standard","I53";
;
CDS_LIB"standard"
BODY_TYPE"PLUMBING"
HDL_TAP"TRUE";
"B \NAC \NWC"14;
"S \NAC"
BN"17"118;
%"TAP"
"1","(-650,2000)","0","standard","I54";
;
CDS_LIB"standard"
BODY_TYPE"PLUMBING"
HDL_TAP"TRUE";
"B \NAC \NWC"14;
"S \NAC"
BN"18"117;
%"TAP"
"1","(-650,2050)","0","standard","I55";
;
CDS_LIB"standard"
BODY_TYPE"PLUMBING"
HDL_TAP"TRUE";
"B \NAC \NWC"14;
"S \NAC"
BN"19"116;
%"TAP"
"1","(-650,2150)","0","standard","I56";
;
CDS_LIB"standard"
BODY_TYPE"PLUMBING"
HDL_TAP"TRUE";
"B \NAC \NWC"14;
"S \NAC"
BN"21"115;
%"TAP"
"1","(-650,2100)","0","standard","I57";
;
CDS_LIB"standard"
BODY_TYPE"PLUMBING"
HDL_TAP"TRUE";
"B \NAC \NWC"14;
"S \NAC"
BN"20"114;
%"TAP"
"1","(-650,2250)","0","standard","I58";
;
CDS_LIB"standard"
BODY_TYPE"PLUMBING"
HDL_TAP"TRUE";
"B \NAC \NWC"14;
"S \NAC"
BN"23"113;
%"TAP"
"1","(-650,2300)","0","standard","I59";
;
CDS_LIB"standard"
BODY_TYPE"PLUMBING"
HDL_TAP"TRUE";
"B \NAC \NWC"14;
"S \NAC"
BN"24"112;
%"TAP"
"1","(-650,3950)","0","standard","I6";
;
CDS_LIB"standard"
BODY_TYPE"PLUMBING"
HDL_TAP"TRUE";
"B \NAC \NWC"15;
"S \NAC"
BN"24"80;
%"TAP"
"1","(-650,2200)","0","standard","I60";
;
CDS_LIB"standard"
BODY_TYPE"PLUMBING"
HDL_TAP"TRUE";
"B \NAC \NWC"14;
"S \NAC"
BN"22"111;
%"TAP"
"1","(-650,2350)","0","standard","I61";
;
CDS_LIB"standard"
BODY_TYPE"PLUMBING"
HDL_TAP"TRUE";
"B \NAC \NWC"14;
"S \NAC"
BN"25"110;
%"TAP"
"1","(-650,2400)","0","standard","I62";
;
CDS_LIB"standard"
BODY_TYPE"PLUMBING"
HDL_TAP"TRUE";
"B \NAC \NWC"14;
"S \NAC"
BN"26"109;
%"TAP"
"1","(-650,2450)","0","standard","I63";
;
CDS_LIB"standard"
BODY_TYPE"PLUMBING"
HDL_TAP"TRUE";
"B \NAC \NWC"14;
"S \NAC"
BN"27"108;
%"TAP"
"1","(-650,2550)","0","standard","I64";
;
CDS_LIB"standard"
BODY_TYPE"PLUMBING"
HDL_TAP"TRUE";
"B \NAC \NWC"14;
"S \NAC"
BN"29"27;
%"TAP"
"1","(-650,2500)","0","standard","I65";
;
CDS_LIB"standard"
BODY_TYPE"PLUMBING"
HDL_TAP"TRUE";
"B \NAC \NWC"14;
"S \NAC"
BN"28"107;
%"TAP"
"1","(-650,2600)","0","standard","I66";
;
CDS_LIB"standard"
BODY_TYPE"PLUMBING"
HDL_TAP"TRUE";
"B \NAC \NWC"14;
"S \NAC"
BN"30"105;
%"TAP"
"1","(-650,2650)","0","standard","I67";
;
CDS_LIB"standard"
BODY_TYPE"PLUMBING"
HDL_TAP"TRUE";
"B \NAC \NWC"14;
"S \NAC"
BN"31"106;
%"TAP"
"1","(-650,1100)","0","standard","I69";
;
CDS_LIB"standard"
BODY_TYPE"PLUMBING"
HDL_TAP"TRUE";
"B \NAC \NWC"14;
"S \NAC"
BN"0"135;
%"TAP"
"1","(-650,4000)","0","standard","I7";
;
CDS_LIB"standard"
BODY_TYPE"PLUMBING"
HDL_TAP"TRUE";
"B \NAC \NWC"15;
"S \NAC"
BN"25"79;
%"TAP"
"1","(2200,4000)","0","standard","I72";
;
CDS_LIB"standard"
BODY_TYPE"PLUMBING"
HDL_TAP"TRUE";
"B \NAC \NWC"18;
"S \NAC"
BN"6"36;
%"TAP"
"1","(2200,4100)","0","standard","I74";
;
CDS_LIB"standard"
BODY_TYPE"PLUMBING"
HDL_TAP"TRUE";
"B \NAC \NWC"18;
"S \NAC"
BN"7"32;
%"TAP"
"1","(2200,4200)","0","standard","I75";
;
CDS_LIB"standard"
BODY_TYPE"PLUMBING"
HDL_TAP"TRUE";
"B \NAC \NWC"18;
"S \NAC"
BN"8"31;
%"TAP"
"1","(2200,4300)","0","standard","I78";
;
CDS_LIB"standard"
BODY_TYPE"PLUMBING"
HDL_TAP"TRUE";
"B \NAC \NWC"18;
"S \NAC"
BN"9"30;
%"TAP"
"1","(-650,4100)","0","standard","I8";
;
CDS_LIB"standard"
BODY_TYPE"PLUMBING"
HDL_TAP"TRUE";
"B \NAC \NWC"15;
"S \NAC"
BN"27"71;
%"TAP"
"1","(2200,3700)","0","standard","I80";
;
CDS_LIB"standard"
BODY_TYPE"PLUMBING"
HDL_TAP"TRUE";
"B \NAC \NWC"18;
"S \NAC"
BN"3"42;
%"TAP"
"1","(2200,3800)","0","standard","I82";
;
CDS_LIB"standard"
BODY_TYPE"PLUMBING"
HDL_TAP"TRUE";
"B \NAC \NWC"18;
"S \NAC"
BN"4"40;
%"TAP"
"1","(2200,3900)","0","standard","I84";
;
CDS_LIB"standard"
BODY_TYPE"PLUMBING"
HDL_TAP"TRUE";
"B \NAC \NWC"18;
"S \NAC"
BN"5"37;
%"TAP"
"1","(2200,3400)","0","standard","I87";
;
CDS_LIB"standard"
BODY_TYPE"PLUMBING"
HDL_TAP"TRUE";
"B \NAC \NWC"18;
"S \NAC"
BN"0"47;
%"TAP"
"1","(2200,3600)","0","standard","I88";
;
CDS_LIB"standard"
BODY_TYPE"PLUMBING"
HDL_TAP"TRUE";
"B \NAC \NWC"18;
"S \NAC"
BN"2"41;
%"TAP"
"1","(2200,3500)","0","standard","I89";
;
CDS_LIB"standard"
BODY_TYPE"PLUMBING"
HDL_TAP"TRUE";
"B \NAC \NWC"18;
"S \NAC"
BN"1"46;
%"TAP"
"1","(-650,4050)","0","standard","I9";
;
CDS_LIB"standard"
BODY_TYPE"PLUMBING"
HDL_TAP"TRUE";
"B \NAC \NWC"15;
"S \NAC"
BN"26"78;
%"TAP"
"1","(2375,3750)","0","standard","I90";
;
CDS_LIB"standard"
BODY_TYPE"PLUMBING"
HDL_TAP"TRUE";
"B \NAC \NWC"19;
"S \NAC"
BN"4"38;
%"TAP"
"1","(2375,3950)","0","standard","I91";
;
CDS_LIB"standard"
BODY_TYPE"PLUMBING"
HDL_TAP"TRUE";
"B \NAC \NWC"19;
"S \NAC"
BN"6"35;
%"TAP"
"1","(2375,4050)","0","standard","I92";
;
CDS_LIB"standard"
BODY_TYPE"PLUMBING"
HDL_TAP"TRUE";
"B \NAC \NWC"19;
"S \NAC"
BN"7"33;
%"TAP"
"1","(2375,4150)","0","standard","I93";
;
CDS_LIB"standard"
BODY_TYPE"PLUMBING"
HDL_TAP"TRUE";
"B \NAC \NWC"19;
"S \NAC"
BN"8"29;
%"TAP"
"1","(2375,4250)","0","standard","I94";
;
CDS_LIB"standard"
BODY_TYPE"PLUMBING"
HDL_TAP"TRUE";
"B \NAC \NWC"19;
"S \NAC"
BN"9"28;
%"TAP"
"1","(2375,3850)","0","standard","I95";
;
CDS_LIB"standard"
BODY_TYPE"PLUMBING"
HDL_TAP"TRUE";
"B \NAC \NWC"19;
"S \NAC"
BN"5"34;
%"TAP"
"1","(2375,3550)","0","standard","I96";
;
CDS_LIB"standard"
BODY_TYPE"PLUMBING"
HDL_TAP"TRUE";
"B \NAC \NWC"19;
"S \NAC"
BN"2"43;
%"TAP"
"1","(2375,3650)","0","standard","I97";
;
CDS_LIB"standard"
BODY_TYPE"PLUMBING"
HDL_TAP"TRUE";
"B \NAC \NWC"19;
"S \NAC"
BN"3"39;
%"TAP"
"1","(2375,3350)","0","standard","I98";
;
CDS_LIB"standard"
BODY_TYPE"PLUMBING"
HDL_TAP"TRUE";
"B \NAC \NWC"19;
"S \NAC"
BN"0"45;
%"TAP"
"1","(2375,3450)","0","standard","I99";
;
CDS_LIB"standard"
BODY_TYPE"PLUMBING"
HDL_TAP"TRUE";
"B \NAC \NWC"19;
"S \NAC"
BN"1"44;
END.
